# S9S_MB_2U (Grand Teton) — schematic netlist excerpt (pin names and nets, part order shuffled) for the footprints in the layout excerpt that follows; sources: Cadence DE-HDL packaged netlist, KiCad conversion of 03242023_DA0F0TMBIJ0_F0T_Motherboard_J_brd_V01_OCP.brd

R4690  Q_RES  33.2 1% EMPTY  pkg 0402LF  page 251 : A = SMB_LM75_0_3V3AUX_SDA ; B = SMB_HSC_TYPE_ADC_SDA
R971  Q_RES  240 1% CHIP  pkg 0402LF  page 236 : A = PVNN_TERM_CPU0 ; B = SMB_S3M_CPU0_R_SDA

(kicad_pcb
	(version 20260206)
	(generator "pcbnew")
	(generator_version "10.0")
	(general
		(thickness 1.6)
		(legacy_teardrops no)
	)
	(paper "A4")
	(title_block
		(title "03242023_DA0F0TMBIJ0_F0T_Motherboard_J_brd_V01_OCP.brd")
		(comment 1 "Grand Teton / footprints 3948-3949 of 6105")
	)
	(layers
		(0 "F.Cu" signal "TOP")
		(4 "In1.Cu" signal "GND")
		(6 "In2.Cu" signal "IN1")
		(8 "In3.Cu" signal "GND1")
		(10 "In4.Cu" signal "IN2")
		(12 "In5.Cu" signal "GND2")
		(14 "In6.Cu" signal "IN3")
		(16 "In7.Cu" signal "GND3")
		(18 "In8.Cu" signal "VCC")
		(20 "In9.Cu" signal "VCC1")
		(22 "In10.Cu" signal "GND4")
		(24 "In11.Cu" signal "IN4")
		(26 "In12.Cu" signal "GND5")
		(28 "In13.Cu" signal "IN5")
		(30 "In14.Cu" signal "GND6")
		(32 "In15.Cu" signal "IN6")
		(34 "In16.Cu" signal "GND7")
		(2 "B.Cu" signal "BOTTOM")
		(9 "F.Adhes" user "F.Adhesive")
		(11 "B.Adhes" user "B.Adhesive")
		(13 "F.Paste" user "Package Geometry/Pastemask Top")
		(15 "B.Paste" user "Package Geometry/Pastemask Bottom")
		(5 "F.SilkS" user "Ref Des/Silkscreen Top")
		(7 "B.SilkS" user "Ref Des/Silkscreen Bottom")
		(1 "F.Mask" user "Board Geometry/Soldermask Top")
		(3 "B.Mask" user "Board Geometry/Soldermask Bottom")
		(17 "Dwgs.User" user "User.Drawings")
		(19 "Cmts.User" user "User.Comments")
		(21 "Eco1.User" user "User.Eco1")
		(23 "Eco2.User" user "User.Eco2")
		(25 "Edge.Cuts" user "Board Geometry/Outline")
		(27 "Margin" user)
		(31 "F.CrtYd" user "Package Geometry/Place Bound Top")
		(29 "B.CrtYd" user "Package Geometry/Place Bound Bottom")
		(35 "F.Fab" user "Ref Des/Assembly Top")
		(33 "B.Fab" user "Ref Des/Assembly Bottom")
	)
	(footprint ""
		(layer "F.Cu")
		(at 294.045894 -412.07436)
		(property "Reference" "R4690"
			(at 0 0 0)
			(layer "F.SilkS")
			(hide yes)
			(effects
				(font
					(size 1.27 1.27)
				)
			)
		)
		(property "Value" ""
			(at 0 0 0)
			(layer "F.Fab")
			(effects
				(font
					(size 1.27 1.27)
				)
			)
		)
		(duplicate_pad_numbers_are_jumpers no)
		(fp_line
			(start -0.7874 -0.4064)
			(end 0.7874 -0.4064)
			(stroke
				(width 0.1524)
				(type default)
			)
			(layer "F.SilkS")
		)
		(fp_line
			(start -0.7874 0.4064)
			(end -0.7874 -0.4064)
			(stroke
				(width 0.1524)
				(type default)
			)
			(layer "F.SilkS")
		)
		(fp_line
			(start 0.7874 -0.4064)
			(end 0.7874 0.4064)
			(stroke
				(width 0.1524)
				(type default)
			)
			(layer "F.SilkS")
		)
		(fp_line
			(start 0.7874 0.4064)
			(end -0.7874 0.4064)
			(stroke
				(width 0.1524)
				(type default)
			)
			(layer "F.SilkS")
		)
		(fp_line
			(start -0.67945 -0.305054)
			(end -0.12065 -0.305054)
			(stroke
				(width 0.1)
				(type default)
			)
			(layer "F.Fab")
		)
		(fp_line
			(start -0.67945 0.3048)
			(end -0.67945 -0.305054)
			(stroke
				(width 0.1)
				(type default)
			)
			(layer "F.Fab")
		)
		(fp_line
			(start -0.12065 -0.305054)
			(end -0.12065 -0.2794)
			(stroke
				(width 0.1)
				(type default)
			)
			(layer "F.Fab")
		)
		(fp_line
			(start -0.12065 -0.2794)
			(end 0.12065 -0.2794)
			(stroke
				(width 0.1)
				(type default)
			)
			(layer "F.Fab")
		)
		(fp_line
			(start -0.12065 0.2794)
			(end -0.12065 0.3048)
			(stroke
				(width 0.1)
				(type default)
			)
			(layer "F.Fab")
		)
		(fp_line
			(start -0.12065 0.3048)
			(end -0.67945 0.3048)
			(stroke
				(width 0.1)
				(type default)
			)
			(layer "F.Fab")
		)
		(fp_line
			(start 0.120396 0.2794)
			(end -0.12065 0.2794)
			(stroke
				(width 0.1)
				(type default)
			)
			(layer "F.Fab")
		)
		(fp_line
			(start 0.120396 0.3048)
			(end 0.120396 0.2794)
			(stroke
				(width 0.1)
				(type default)
			)
			(layer "F.Fab")
		)
		(fp_line
			(start 0.12065 -0.3048)
			(end 0.67945 -0.3048)
			(stroke
				(width 0.1)
				(type default)
			)
			(layer "F.Fab")
		)
		(fp_line
			(start 0.12065 -0.2794)
			(end 0.12065 -0.3048)
			(stroke
				(width 0.1)
				(type default)
			)
			(layer "F.Fab")
		)
		(fp_line
			(start 0.67945 -0.3048)
			(end 0.67945 0.3048)
			(stroke
				(width 0.1)
				(type default)
			)
			(layer "F.Fab")
		)
		(fp_line
			(start 0.67945 0.3048)
			(end 0.120396 0.3048)
			(stroke
				(width 0.1)
				(type default)
			)
			(layer "F.Fab")
		)
		(pad "1" smd circle
			(at -0.40005 0)
			(size 0 0)
			(layers "F.Cu" "F.Mask" "F.Paste")
			(net "SMB_LM75_0_3V3AUX_SDA")
		)
		(pad "2" smd circle
			(at 0.40005 0)
			(size 0 0)
			(layers "F.Cu" "F.Mask" "F.Paste")
			(net "SMB_HSC_TYPE_ADC_SDA")
		)
	)
	(footprint ""
		(layer "F.Cu")
		(at 392.363198 -161.07791)
		(property "Reference" "R971"
			(at 0 0 0)
			(layer "F.SilkS")
			(hide yes)
			(effects
				(font
					(size 1.27 1.27)
				)
			)
		)
		(property "Value" ""
			(at 0 0 0)
			(layer "F.Fab")
			(effects
				(font
					(size 1.27 1.27)
				)
			)
		)
		(duplicate_pad_numbers_are_jumpers no)
		(fp_line
			(start -0.7874 -0.4064)
			(end 0.7874 -0.4064)
			(stroke
				(width 0.1524)
				(type default)
			)
			(layer "F.SilkS")
		)
		(fp_line
			(start -0.7874 0.4064)
			(end -0.7874 -0.4064)
			(stroke
				(width 0.1524)
				(type default)
			)
			(layer "F.SilkS")
		)
		(fp_line
			(start 0.7874 -0.4064)
			(end 0.7874 0.4064)
			(stroke
				(width 0.1524)
				(type default)
			)
			(layer "F.SilkS")
		)
		(fp_line
			(start 0.7874 0.4064)
			(end -0.7874 0.4064)
			(stroke
				(width 0.1524)
				(type default)
			)
			(layer "F.SilkS")
		)
		(fp_line
			(start -0.67945 -0.305054)
			(end -0.12065 -0.305054)
			(stroke
				(width 0.1)
				(type default)
			)
			(layer "F.Fab")
		)
		(fp_line
			(start -0.67945 0.3048)
			(end -0.67945 -0.305054)
			(stroke
				(width 0.1)
				(type default)
			)
			(layer "F.Fab")
		)
		(fp_line
			(start -0.12065 -0.305054)
			(end -0.12065 -0.2794)
			(stroke
				(width 0.1)
				(type default)
			)
			(layer "F.Fab")
		)
		(fp_line
			(start -0.12065 -0.2794)
			(end 0.12065 -0.2794)
			(stroke
				(width 0.1)
				(type default)
			)
			(layer "F.Fab")
		)
		(fp_line
			(start -0.12065 0.2794)
			(end -0.12065 0.3048)
			(stroke
				(width 0.1)
				(type default)
			)
			(layer "F.Fab")
		)
		(fp_line
			(start -0.12065 0.3048)
			(end -0.67945 0.3048)
			(stroke
				(width 0.1)
				(type default)
			)
			(layer "F.Fab")
		)
		(fp_line
			(start 0.120396 0.2794)
			(end -0.12065 0.2794)
			(stroke
				(width 0.1)
				(type default)
			)
			(layer "F.Fab")
		)
		(fp_line
			(start 0.120396 0.3048)
			(end 0.120396 0.2794)
			(stroke
				(width 0.1)
				(type default)
			)
			(layer "F.Fab")
		)
		(fp_line
			(start 0.12065 -0.3048)
			(end 0.67945 -0.3048)
			(stroke
				(width 0.1)
				(type default)
			)
			(layer "F.Fab")
		)
		(fp_line
			(start 0.12065 -0.2794)
			(end 0.12065 -0.3048)
			(stroke
				(width 0.1)
				(type default)
			)
			(layer "F.Fab")
		)
		(fp_line
			(start 0.67945 -0.3048)
			(end 0.67945 0.3048)
			(stroke
				(width 0.1)
				(type default)
			)
			(layer "F.Fab")
		)
		(fp_line
			(start 0.67945 0.3048)
			(end 0.120396 0.3048)
			(stroke
				(width 0.1)
				(type default)
			)
			(layer "F.Fab")
		)
		(pad "1" smd circle
			(at -0.40005 0)
			(size 0 0)
			(layers "F.Cu" "F.Mask" "F.Paste")
			(net "PVNN_TERM_CPU0")
		)
		(pad "2" smd circle
			(at 0.40005 0)
			(size 0 0)
			(layers "F.Cu" "F.Mask" "F.Paste")
			(net "SMB_S3M_CPU0_R_SDA")
		)
	)
)
